(kicad_pcb
	(version 20260206)
	(generator "pcbnew")
	(generator_version "10.0")
	(general
		(thickness 1.21888)
		(legacy_teardrops no)
	)
	(paper "A4")
	(title_block
		(title "timecard-v9 — TimeCard-DC-V9_EXP.PcbDoc")
		(comment 1 "Time Appliance Project (Time Card) / footprints 201-208 of 402")
	)
	(layers
		(0 "F.Cu" signal "TOP")
		(4 "In1.Cu" signal "SGND")
		(6 "In2.Cu" signal "IN1")
		(8 "In3.Cu" signal "IN2")
		(10 "In4.Cu" signal "SGND1")
		(2 "B.Cu" signal "BOTTOM")
		(9 "F.Adhes" user "F.Adhesive")
		(11 "B.Adhes" user "B.Adhesive")
		(13 "F.Paste" user "Top Paste")
		(15 "B.Paste" user "Bottom Paste")
		(5 "F.SilkS" user "Top Overlay")
		(7 "B.SilkS" user "Bottom Overlay")
		(1 "F.Mask" user "Top Solder")
		(3 "B.Mask" user "Bottom Solder")
		(17 "Dwgs.User" user "User.Drawings")
		(19 "Cmts.User" user "User.Comments")
		(21 "Eco1.User" user "User.Eco1")
		(23 "Eco2.User" user "User.Eco2")
		(25 "Edge.Cuts" user)
		(27 "Margin" user)
		(31 "F.CrtYd" user "Top Courtyard")
		(29 "B.CrtYd" user "Bottom Courtyard")
		(35 "F.Fab" user "Top Component Center")
		(33 "B.Fab" user "Bottom Component Center")
	)
	(footprint "Vault:RGV0016A_V"
		(layer "F.Cu")
		(at 170.3216 114.6162 90)
		(property "Reference" "U27"
			(at 2.973079 -1.6968 0)
			(unlocked yes)
			(layer "F.SilkS")
			(effects
				(font
					(size 0.762 0.762)
					(thickness 0.2032)
				)
			)
		)
		(property "Value" "PCA9546ARGVR"
			(at 7.020225 3.875271 90)
			(unlocked yes)
			(layer "F.SilkS")
			(hide yes)
			(effects
				(font
					(size 0.762 0.762)
					(thickness 0.2032)
				)
			)
		)
		(sheetname "08-DIPSwitches_I2C")
		(sheetfile "08-DIPSwitches_I2C.kicad_sch")
		(duplicate_pad_numbers_are_jumpers no)
		(fp_line
			(start 2.225 -2.225)
			(end 2.225 -1.925)
			(stroke
				(width 0.2)
				(type solid)
			)
			(layer "F.SilkS")
		)
		(fp_line
			(start 1.925 -2.225)
			(end 2.225 -2.225)
			(stroke
				(width 0.2)
				(type solid)
			)
			(layer "F.SilkS")
		)
		(fp_line
			(start -2.225 -2.225)
			(end -1.525 -2.225)
			(stroke
				(width 0.2)
				(type solid)
			)
			(layer "F.SilkS")
		)
		(fp_line
			(start -2.225 -2.225)
			(end -2.225 -1.525)
			(stroke
				(width 0.2)
				(type solid)
			)
			(layer "F.SilkS")
		)
		(fp_line
			(start 2.225 1.925)
			(end 2.225 2.225)
			(stroke
				(width 0.2)
				(type solid)
			)
			(layer "F.SilkS")
		)
		(fp_line
			(start -2.225 1.925)
			(end -2.225 2.225)
			(stroke
				(width 0.2)
				(type solid)
			)
			(layer "F.SilkS")
		)
		(fp_line
			(start 1.925 2.225)
			(end 2.225 2.225)
			(stroke
				(width 0.2)
				(type solid)
			)
			(layer "F.SilkS")
		)
		(fp_line
			(start -2.225 2.225)
			(end -1.925 2.225)
			(stroke
				(width 0.2)
				(type solid)
			)
			(layer "F.SilkS")
		)
		(fp_poly
			(pts
				(xy -0.987355 -0.987355) (xy -0.987355 -0.151645) (xy -0.151645 -0.151645) (xy -0.151645 -0.987355)
			)
			(stroke
				(width 0.10329)
				(type solid)
			)
			(fill yes)
			(layer "F.Paste")
		)
		(fp_poly
			(pts
				(xy 0.987355 -0.151645) (xy 0.987355 -0.987355) (xy 0.151645 -0.987355) (xy 0.151645 -0.151645)
			)
			(stroke
				(width 0.10329)
				(type solid)
			)
			(fill yes)
			(layer "F.Paste")
		)
		(fp_poly
			(pts
				(xy -0.987355 0.151645) (xy -0.987355 0.987355) (xy -0.151645 0.987355) (xy -0.151645 0.151645)
			)
			(stroke
				(width 0.10329)
				(type solid)
			)
			(fill yes)
			(layer "F.Paste")
		)
		(fp_poly
			(pts
				(xy 0.987355 0.987355) (xy 0.987355 0.151645) (xy 0.151645 0.151645) (xy 0.151645 0.987355)
			)
			(stroke
				(width 0.10329)
				(type solid)
			)
			(fill yes)
			(layer "F.Paste")
		)
		(pad "1" smd roundrect
			(at -1.825 -0.975 180)
			(size 0.3 0.75)
			(layers "F.Cu" "F.Mask" "F.Paste")
			(roundrect_rratio 0.165)
			(net "NetR121_2")
		)
		(pad "2" smd roundrect
			(at -1.825 -0.325 180)
			(size 0.3 0.75)
			(layers "F.Cu" "F.Mask" "F.Paste")
			(roundrect_rratio 0.165)
			(net "MAC_I2C_SDA")
		)
		(pad "3" smd roundrect
			(at -1.825 0.325 180)
			(size 0.3 0.75)
			(layers "F.Cu" "F.Mask" "F.Paste")
			(roundrect_rratio 0.165)
			(net "MAC_I2C_SCL")
		)
		(pad "4" smd roundrect
			(at -1.825 0.975 180)
			(size 0.3 0.75)
			(layers "F.Cu" "F.Mask" "F.Paste")
			(roundrect_rratio 0.165)
			(net "SENS_I2C_SDA")
		)
		(pad "5" smd roundrect
			(at -0.975 1.825 90)
			(size 0.3 0.75)
			(layers "F.Cu" "F.Mask" "F.Paste")
			(roundrect_rratio 0.165)
			(net "SENS_I2C_SCL")
		)
		(pad "6" smd roundrect
			(at -0.325 1.825 90)
			(size 0.3 0.75)
			(layers "F.Cu" "F.Mask" "F.Paste")
			(roundrect_rratio 0.165)
			(net "GND")
		)
		(pad "7" smd roundrect
			(at 0.325 1.825 90)
			(size 0.3 0.75)
			(layers "F.Cu" "F.Mask" "F.Paste")
			(roundrect_rratio 0.165)
			(net "ANADC_I2C_SDA")
		)
		(pad "8" smd roundrect
			(at 0.975 1.825 90)
			(size 0.3 0.75)
			(layers "F.Cu" "F.Mask" "F.Paste")
			(roundrect_rratio 0.165)
			(net "ANADC_I2C_SCL")
		)
		(pad "9" smd roundrect
			(at 1.825 0.975 180)
			(size 0.3 0.75)
			(layers "F.Cu" "F.Mask" "F.Paste")
			(roundrect_rratio 0.165)
			(net "DC_I2C_SDA")
		)
		(pad "10" smd roundrect
			(at 1.825 0.325 180)
			(size 0.3 0.75)
			(layers "F.Cu" "F.Mask" "F.Paste")
			(roundrect_rratio 0.165)
			(net "DC_I2C_SCL")
		)
		(pad "11" smd roundrect
			(at 1.825 -0.325 180)
			(size 0.3 0.75)
			(layers "F.Cu" "F.Mask" "F.Paste")
			(roundrect_rratio 0.165)
			(net "NetR126_2")
		)
		(pad "12" smd roundrect
			(at 1.825 -0.975 180)
			(size 0.3 0.75)
			(layers "F.Cu" "F.Mask" "F.Paste")
			(roundrect_rratio 0.165)
			(net "SCL")
		)
		(pad "13" smd roundrect
			(at 0.975 -1.825 90)
			(size 0.3 0.75)
			(layers "F.Cu" "F.Mask" "F.Paste")
			(roundrect_rratio 0.165)
			(net "SDA")
		)
		(pad "14" smd roundrect
			(at 0.325 -1.825 90)
			(size 0.3 0.75)
			(layers "F.Cu" "F.Mask" "F.Paste")
			(roundrect_rratio 0.165)
			(net "+3.3V")
		)
		(pad "15" smd roundrect
			(at -0.325 -1.825 90)
			(size 0.3 0.75)
			(layers "F.Cu" "F.Mask" "F.Paste")
			(roundrect_rratio 0.165)
			(net "NetR128_2")
		)
		(pad "16" smd roundrect
			(at -0.975 -1.825 90)
			(size 0.3 0.75)
			(layers "F.Cu" "F.Mask" "F.Paste")
			(roundrect_rratio 0.165)
			(net "NetR127_2")
		)
		(pad "17" smd roundrect
			(at 0 0 90)
			(size 2.1 2.1)
			(layers "F.Cu" "F.Mask" "F.Paste")
			(roundrect_rratio 0.025)
			(net "GND")
			(solder_paste_margin -1.08)
		)
	)
	(footprint "Vault:RESC1005X40X25NL05T05"
		(layer "F.Cu")
		(at 108.3216 51.3162 90)
		(property "Reference" "R155"
			(at -0.2968 8.226921 90)
			(unlocked yes)
			(layer "F.SilkS")
			(effects
				(font
					(size 0.762 0.762)
					(thickness 0.2032)
				)
			)
		)
		(property "Value" "DNI_27_1%_0402"
			(at -2.732271 10.270975 0)
			(unlocked yes)
			(layer "F.SilkS")
			(hide yes)
			(effects
				(font
					(size 0.762 0.762)
					(thickness 0.2032)
				)
			)
		)
		(sheetname "11-M2_RCB_MUX")
		(sheetfile "11-M2_RCB_MUX.kicad_sch")
		(duplicate_pad_numbers_are_jumpers no)
		(pad "1" smd rect
			(at -0.45 0 180)
			(size 0.55 0.55)
			(layers "F.Cu" "F.Mask" "F.Paste")
			(net "RCB_GPS1_TX")
		)
		(pad "2" smd rect
			(at 0.45 0 180)
			(size 0.55 0.55)
			(layers "F.Cu" "F.Mask" "F.Paste")
			(net "GPS1_TX")
		)
	)
	(footprint "SA53:SolderSocket"
		(locked yes)
		(layer "F.Cu")
		(at 86.9216 96.7162 90)
		(property "Reference" "SKT2"
			(at -0.226921 -6.7714 0)
			(unlocked yes)
			(layer "F.SilkS")
			(effects
				(font
					(size 0.762 0.762)
					(thickness 0.2286)
				)
			)
		)
		(property "Value" "0332-0-43-80-18-27-10-0"
			(at -2.910071 16.1362 0)
			(unlocked yes)
			(layer "F.SilkS")
			(hide yes)
			(effects
				(font
					(size 0.762 0.762)
					(thickness 0.2286)
				)
			)
		)
		(sheetname "06-MAC")
		(sheetfile "06-MAC.kicad_sch")
		(duplicate_pad_numbers_are_jumpers no)
		(pad "1" thru_hole circle
			(at 0 0 90)
			(size 2.54 2.54)
			(drill 2.0066)
			(layers "*.Cu" "*.Mask")
			(remove_unused_layers no)
			(net "MAC_FREQ_CTRL")
			(thermal_bridge_angle 90)
		)
	)
	(footprint "SamacSys:SOP50P310X90-8N"
		(layer "F.Cu")
		(at 77.42159 114.0162 180)
		(property "Reference" "U12"
			(at -0.92861 1.773069 0)
			(unlocked yes)
			(layer "F.SilkS")
			(effects
				(font
					(size 0.762 0.762)
					(thickness 0.2286)
				)
			)
		)
		(property "Value" "NC7WV125K8X"
			(at 6.207715 2.884671 180)
			(unlocked yes)
			(layer "F.SilkS")
			(hide yes)
			(effects
				(font
					(size 0.762 0.762)
					(thickness 0.2286)
				)
			)
		)
		(sheetname "01-USER_IO")
		(sheetfile "01-USER_IO.kicad_sch")
		(duplicate_pad_numbers_are_jumpers no)
		(fp_line
			(start 0.8 1)
			(end -0.8 1)
			(stroke
				(width 0.2)
				(type solid)
			)
			(layer "F.SilkS")
		)
		(fp_line
			(start 0.8 -1)
			(end 0.8 1)
			(stroke
				(width 0.2)
				(type solid)
			)
			(layer "F.SilkS")
		)
		(fp_line
			(start 0.8 -1)
			(end -0.8 -1)
			(stroke
				(width 0.2)
				(type solid)
			)
			(layer "F.SilkS")
		)
		(fp_line
			(start -0.8 -1)
			(end -0.8 1)
			(stroke
				(width 0.2)
				(type solid)
			)
			(layer "F.SilkS")
		)
		(fp_line
			(start -1.15 -1.25)
			(end -2 -1.25)
			(stroke
				(width 0.2)
				(type solid)
			)
			(layer "F.SilkS")
		)
		(pad "1" smd rect
			(at -1.575 -0.75 180)
			(size 0.85 0.3)
			(layers "F.Cu" "F.Mask" "F.Paste")
			(net "ANT2_IO_OUT")
		)
		(pad "2" smd rect
			(at -1.575 -0.25 180)
			(size 0.85 0.3)
			(layers "F.Cu" "F.Mask" "F.Paste")
			(net "ANT2_OUT")
		)
		(pad "3" smd rect
			(at -1.575 0.25 180)
			(size 0.85 0.3)
			(layers "F.Cu" "F.Mask" "F.Paste")
			(net "ANT2_IN")
		)
		(pad "4" smd rect
			(at -1.575 0.75 180)
			(size 0.85 0.3)
			(layers "F.Cu" "F.Mask" "F.Paste")
			(net "GND")
		)
		(pad "5" smd rect
			(at 1.575 0.75 180)
			(size 0.85 0.3)
			(layers "F.Cu" "F.Mask" "F.Paste")
			(net "NetR33_1")
		)
		(pad "6" smd rect
			(at 1.575 0.25 180)
			(size 0.85 0.3)
			(layers "F.Cu" "F.Mask" "F.Paste")
			(net "NetR33_1")
		)
		(pad "7" smd rect
			(at 1.575 -0.25 180)
			(size 0.85 0.3)
			(layers "F.Cu" "F.Mask" "F.Paste")
			(net "ANT2_IO_IN")
		)
		(pad "8" smd rect
			(at 1.575 -0.75 180)
			(size 0.85 0.3)
			(layers "F.Cu" "F.Mask" "F.Paste")
			(net "+3.3V")
		)
	)
	(footprint "Vault:FP-DFN-12-IPC_B"
		(layer "F.Cu")
		(at 228.3966 116.3317 90)
		(property "Reference" "U20"
			(at -0.3131 2.698069 270)
			(unlocked yes)
			(layer "F.SilkS")
			(effects
				(font
					(size 0.762 0.762)
					(thickness 0.2286)
				)
			)
		)
		(property "Value" "FT234XD-R"
			(at 4.45556 3.392671 90)
			(unlocked yes)
			(layer "F.SilkS")
			(hide yes)
			(effects
				(font
					(size 0.762 0.762)
					(thickness 0.2286)
				)
			)
		)
		(sheetname "09-USBUart_PPSMUX_UARTMUX")
		(sheetfile "09-USBUart_PPSMUX_UARTMUX.kicad_sch")
		(duplicate_pad_numbers_are_jumpers no)
		(fp_line
			(start -1.5 -1.625)
			(end 1.5 -1.625)
			(stroke
				(width 0.2)
				(type solid)
			)
			(layer "F.SilkS")
		)
		(fp_line
			(start -1.5 1.625)
			(end 1.5 1.625)
			(stroke
				(width 0.2)
				(type solid)
			)
			(layer "F.SilkS")
		)
		(fp_circle
			(center -2.38536 -1.125)
			(end -2.26036 -1.125)
			(stroke
				(width 0.25)
				(type solid)
			)
			(fill no)
			(layer "F.SilkS")
		)
		(fp_rect
			(start -0.46147 0.91168)
			(end 0.46167 -0.91146)
			(stroke
				(width 0)
				(type default)
			)
			(fill yes)
			(layer "F.Paste")
		)
		(fp_line
			(start 2.08535 -1.75)
			(end 2.08535 1.75)
			(stroke
				(width 0.2)
				(type solid)
			)
			(layer "F.CrtYd")
		)
		(fp_line
			(start -2.08536 -1.75)
			(end 2.08535 -1.75)
			(stroke
				(width 0.2)
				(type solid)
			)
			(layer "F.CrtYd")
		)
		(fp_line
			(start -2.08536 -1.75)
			(end -2.08536 1.75)
			(stroke
				(width 0.2)
				(type solid)
			)
			(layer "F.CrtYd")
		)
		(fp_line
			(start -2.08536 1.75)
			(end 2.08535 1.75)
			(stroke
				(width 0.2)
				(type solid)
			)
			(layer "F.CrtYd")
		)
		(fp_line
			(start 2.08535 -1.75)
			(end 2.08535 1.75)
			(stroke
				(width 0.2)
				(type solid)
			)
			(layer "F.Fab")
		)
		(fp_line
			(start -2.08536 -1.75)
			(end 2.08535 -1.75)
			(stroke
				(width 0.2)
				(type solid)
			)
			(layer "F.Fab")
		)
		(fp_line
			(start -2.08536 -1.75)
			(end -2.08536 1.75)
			(stroke
				(width 0.2)
				(type solid)
			)
			(layer "F.Fab")
		)
		(fp_line
			(start 0 -0.5)
			(end 0 0.5)
			(stroke
				(width 0.1)
				(type solid)
			)
			(layer "F.Fab")
		)
		(fp_line
			(start -0.5 0)
			(end 0.5 0)
			(stroke
				(width 0.1)
				(type solid)
			)
			(layer "F.Fab")
		)
		(fp_line
			(start -2.08536 1.75)
			(end 2.08535 1.75)
			(stroke
				(width 0.2)
				(type solid)
			)
			(layer "F.Fab")
		)
		(fp_text user "${REFERENCE}"
			(at 0 0.28425 90)
			(unlocked yes)
			(layer "F.Fab")
			(effects
				(font
					(face "Arial")
					(size 0.63 0.63)
					(thickness 0.1)
				)
				(justify left bottom)
			)
		)
		(pad "1" smd rect
			(at -1.4155 -1.125 90)
			(size 0.83971 0.22247)
			(layers "F.Cu" "F.Mask" "F.Paste")
			(net "FTDI_USB_N")
			(solder_mask_margin 0)
			(solder_paste_margin 0)
		)
		(pad "2" smd roundrect
			(at -1.4155 -0.675 90)
			(size 0.83971 0.22247)
			(layers "F.Cu" "F.Mask" "F.Paste")
			(roundrect_rratio 0.5)
			(net "NetC91_1")
			(solder_mask_margin 0)
			(solder_paste_margin 0)
		)
		(pad "3" smd roundrect
			(at -1.4155 -0.225 90)
			(size 0.83971 0.22247)
			(layers "F.Cu" "F.Mask" "F.Paste")
			(roundrect_rratio 0.5)
			(net "NetC92_1")
			(solder_mask_margin 0)
			(solder_paste_margin 0)
		)
		(pad "4" smd roundrect
			(at -1.4155 0.225 90)
			(size 0.83971 0.22247)
			(layers "F.Cu" "F.Mask" "F.Paste")
			(roundrect_rratio 0.5)
			(net "FTDI_VBUS")
			(solder_mask_margin 0)
			(solder_paste_margin 0)
		)
		(pad "5" smd roundrect
			(at -1.4155 0.675 90)
			(size 0.83971 0.22247)
			(layers "F.Cu" "F.Mask" "F.Paste")
			(roundrect_rratio 0.5)
			(net "GND")
			(solder_mask_margin 0)
			(solder_paste_margin 0)
		)
		(pad "6" smd roundrect
			(at -1.4155 1.125 90)
			(size 0.83971 0.22247)
			(layers "F.Cu" "F.Mask" "F.Paste")
			(roundrect_rratio 0.5)
			(solder_mask_margin 0)
			(solder_paste_margin 0)
		)
		(pad "7" smd roundrect
			(at 1.4155 1.125 90)
			(size 0.83971 0.22247)
			(layers "F.Cu" "F.Mask" "F.Paste")
			(roundrect_rratio 0.5)
			(net "NetR13_1")
			(solder_mask_margin 0)
			(solder_paste_margin 0)
		)
		(pad "8" smd roundrect
			(at 1.4155 0.675 90)
			(size 0.83971 0.22247)
			(layers "F.Cu" "F.Mask" "F.Paste")
			(roundrect_rratio 0.5)
			(solder_mask_margin 0)
			(solder_paste_margin 0)
		)
		(pad "9" smd roundrect
			(at 1.4155 0.225 90)
			(size 0.83971 0.22247)
			(layers "F.Cu" "F.Mask" "F.Paste")
			(roundrect_rratio 0.5)
			(net "NetC92_1")
			(solder_mask_margin 0)
			(solder_paste_margin 0)
		)
		(pad "10" smd roundrect
			(at 1.4155 -0.225 90)
			(size 0.83971 0.22247)
			(layers "F.Cu" "F.Mask" "F.Paste")
			(roundrect_rratio 0.5)
			(net "NetR42_1")
			(solder_mask_margin 0)
			(solder_paste_margin 0)
		)
		(pad "11" smd roundrect
			(at 1.4155 -0.675 90)
			(size 0.83971 0.22247)
			(layers "F.Cu" "F.Mask" "F.Paste")
			(roundrect_rratio 0.5)
			(solder_mask_margin 0)
			(solder_paste_margin 0)
		)
		(pad "12" smd roundrect
			(at 1.4155 -1.125 90)
			(size 0.83971 0.22247)
			(layers "F.Cu" "F.Mask" "F.Paste")
			(roundrect_rratio 0.5)
			(net "FTDI_USB_P")
			(solder_mask_margin 0)
			(solder_paste_margin 0)
		)
		(pad "13" smd rect
			(at 0 0 90)
			(size 1.65 2.55)
			(layers "F.Cu" "F.Mask" "F.Paste")
			(net "GND")
			(solder_mask_margin 0)
			(solder_paste_margin -1000)
		)
	)
	(footprint "Passives:SOT65P210X110-3N"
		(layer "F.Cu")
		(at 179.80761 145.49763)
		(property "Reference" "D5"
			(at -3.38526 -0.968085 0)
			(unlocked yes)
			(layer "F.SilkS")
			(effects
				(font
					(size 0.762 0.762)
					(thickness 0.2286)
				)
				(justify left bottom)
			)
		)
		(property "Value" "BAT54SW"
			(at -10.77491 -6.323555 0)
			(unlocked yes)
			(layer "F.SilkS")
			(hide yes)
			(effects
				(font
					(size 0.762 0.762)
					(thickness 0.2286)
				)
				(justify left bottom)
			)
		)
		(sheetname "04-PCIe_JTAG")
		(sheetfile "04-PCIe_JTAG.kicad_sch")
		(duplicate_pad_numbers_are_jumpers no)
		(fp_line
			(start -0.325 -1.1)
			(end 0.675 -1.1)
			(stroke
				(width 0.2)
				(type solid)
			)
			(layer "F.SilkS")
		)
		(fp_line
			(start -0.325 1.1)
			(end 0.675 1.1)
			(stroke
				(width 0.2)
				(type solid)
			)
			(layer "F.SilkS")
		)
		(fp_line
			(start 0.675 -0.65)
			(end 0.675 -1.1)
			(stroke
				(width 0.2)
				(type solid)
			)
			(layer "F.SilkS")
		)
		(fp_line
			(start 0.675 1.1)
			(end 0.675 0.65)
			(stroke
				(width 0.2)
				(type solid)
			)
			(layer "F.SilkS")
		)
		(fp_circle
			(center -1.125 -1.45)
			(end -1.125 -1.575)
			(stroke
				(width 0.25)
				(type solid)
			)
			(fill no)
			(layer "F.SilkS")
		)
		(pad "1" smd rect
			(at -1.125 -0.65 90)
			(size 0.5 0.9)
			(layers "F.Cu" "F.Mask" "F.Paste")
			(net "GND")
		)
		(pad "2" smd rect
			(at -1.125 0.65 90)
			(size 0.5 0.9)
			(layers "F.Cu" "F.Mask" "F.Paste")
			(net "+3.3V")
		)
		(pad "3" smd rect
			(at 1.125 0 90)
			(size 0.5 0.9)
			(layers "F.Cu" "F.Mask" "F.Paste")
			(net "FPGA_TCK")
		)
	)
	(footprint "Vault:RESC1005X40X25NL05T05"
		(layer "F.Cu")
		(at 190.5216 130.4162 90)
		(property "Reference" "R148"
			(at -0.5968 -0.973079 90)
			(unlocked yes)
			(layer "F.SilkS")
			(effects
				(font
					(size 0.762 0.762)
					(thickness 0.2032)
				)
			)
		)
		(property "Value" "DNI_27_1%_0402"
			(at -2.732271 10.270965 0)
			(unlocked yes)
			(layer "F.SilkS")
			(hide yes)
			(effects
				(font
					(size 0.762 0.762)
					(thickness 0.2032)
				)
			)
		)
		(sheetname "11-M2_RCB_MUX")
		(sheetfile "11-M2_RCB_MUX.kicad_sch")
		(duplicate_pad_numbers_are_jumpers no)
		(pad "1" smd rect
			(at -0.45 0 180)
			(size 0.55 0.55)
			(layers "F.Cu" "F.Mask" "F.Paste")
			(net "RCB_GPS2_TX")
		)
		(pad "2" smd rect
			(at 0.45 0 180)
			(size 0.55 0.55)
			(layers "F.Cu" "F.Mask" "F.Paste")
			(net "GPS2_TX")
		)
	)
	(footprint "Vault:RESC1005X40X25NL05T05"
		(layer "F.Cu")
		(at 225.1466 115.8162)
		(property "Reference" "R81"
			(at -3.496395 -0.073069 0)
			(unlocked yes)
			(layer "F.SilkS")
			(effects
				(font
					(size 0.762 0.762)
					(thickness 0.2286)
				)
			)
		)
		(property "Value" "27_1%_0402"
			(at -2.732271 7.37632 270)
			(unlocked yes)
			(layer "F.SilkS")
			(hide yes)
			(effects
				(font
					(size 0.762 0.762)
					(thickness 0.2286)
				)
			)
		)
		(sheetname "09-USBUart_PPSMUX_UARTMUX")
		(sheetfile "09-USBUart_PPSMUX_UARTMUX.kicad_sch")
		(duplicate_pad_numbers_are_jumpers no)
		(pad "1" smd rect
			(at -0.45 0 90)
			(size 0.55 0.55)
			(layers "F.Cu" "F.Mask" "F.Paste")
			(net "FTDI_USB_R_P")
		)
		(pad "2" smd rect
			(at 0.45 0 90)
			(size 0.55 0.55)
			(layers "F.Cu" "F.Mask" "F.Paste")
			(net "FTDI_USB_P")
		)
	)
)
